(kicad_pcb
	(version 20260206)
	(generator "pcbnew")
	(generator_version "10.0")
	(general
		(thickness 1.6)
		(legacy_teardrops no)
	)
	(paper "A4")
	(title_block
		(title "03242023_DA0F0TMBIJ0_F0T_Motherboard_J_brd_V01_OCP.brd")
		(comment 1 "Grand Teton / footprints 1879-1885 of 6105")
	)
	(layers
		(0 "F.Cu" signal "TOP")
		(4 "In1.Cu" signal "GND")
		(6 "In2.Cu" signal "IN1")
		(8 "In3.Cu" signal "GND1")
		(10 "In4.Cu" signal "IN2")
		(12 "In5.Cu" signal "GND2")
		(14 "In6.Cu" signal "IN3")
		(16 "In7.Cu" signal "GND3")
		(18 "In8.Cu" signal "VCC")
		(20 "In9.Cu" signal "VCC1")
		(22 "In10.Cu" signal "GND4")
		(24 "In11.Cu" signal "IN4")
		(26 "In12.Cu" signal "GND5")
		(28 "In13.Cu" signal "IN5")
		(30 "In14.Cu" signal "GND6")
		(32 "In15.Cu" signal "IN6")
		(34 "In16.Cu" signal "GND7")
		(2 "B.Cu" signal "BOTTOM")
		(9 "F.Adhes" user "F.Adhesive")
		(11 "B.Adhes" user "B.Adhesive")
		(13 "F.Paste" user "Package Geometry/Pastemask Top")
		(15 "B.Paste" user "Package Geometry/Pastemask Bottom")
		(5 "F.SilkS" user "Ref Des/Silkscreen Top")
		(7 "B.SilkS" user "Ref Des/Silkscreen Bottom")
		(1 "F.Mask" user "Board Geometry/Soldermask Top")
		(3 "B.Mask" user "Board Geometry/Soldermask Bottom")
		(17 "Dwgs.User" user "User.Drawings")
		(19 "Cmts.User" user "User.Comments")
		(21 "Eco1.User" user "User.Eco1")
		(23 "Eco2.User" user "User.Eco2")
		(25 "Edge.Cuts" user "Board Geometry/Outline")
		(27 "Margin" user)
		(31 "F.CrtYd" user "Package Geometry/Place Bound Top")
		(29 "B.CrtYd" user "Package Geometry/Place Bound Bottom")
		(35 "F.Fab" user "Ref Des/Assembly Top")
		(33 "B.Fab" user "Ref Des/Assembly Bottom")
	)
	(footprint ""
		(layer "F.Cu")
		(at 164.247576 -36.825428)
		(property "Reference" "R4464"
			(at 0 0 0)
			(layer "F.SilkS")
			(hide yes)
			(effects
				(font
					(size 1.27 1.27)
				)
			)
		)
		(property "Value" ""
			(at 0 0 0)
			(layer "F.Fab")
			(effects
				(font
					(size 1.27 1.27)
				)
			)
		)
		(duplicate_pad_numbers_are_jumpers no)
		(fp_line
			(start -0.7874 -0.4064)
			(end 0.7874 -0.4064)
			(stroke
				(width 0.1524)
				(type default)
			)
			(layer "F.SilkS")
		)
		(fp_line
			(start -0.7874 0.4064)
			(end -0.7874 -0.4064)
			(stroke
				(width 0.1524)
				(type default)
			)
			(layer "F.SilkS")
		)
		(fp_line
			(start 0.7874 -0.4064)
			(end 0.7874 0.4064)
			(stroke
				(width 0.1524)
				(type default)
			)
			(layer "F.SilkS")
		)
		(fp_line
			(start 0.7874 0.4064)
			(end -0.7874 0.4064)
			(stroke
				(width 0.1524)
				(type default)
			)
			(layer "F.SilkS")
		)
		(fp_line
			(start -0.67945 -0.305054)
			(end -0.12065 -0.305054)
			(stroke
				(width 0.1)
				(type default)
			)
			(layer "F.Fab")
		)
		(fp_line
			(start -0.67945 0.3048)
			(end -0.67945 -0.305054)
			(stroke
				(width 0.1)
				(type default)
			)
			(layer "F.Fab")
		)
		(fp_line
			(start -0.12065 -0.305054)
			(end -0.12065 -0.2794)
			(stroke
				(width 0.1)
				(type default)
			)
			(layer "F.Fab")
		)
		(fp_line
			(start -0.12065 -0.2794)
			(end 0.12065 -0.2794)
			(stroke
				(width 0.1)
				(type default)
			)
			(layer "F.Fab")
		)
		(fp_line
			(start -0.12065 0.2794)
			(end -0.12065 0.3048)
			(stroke
				(width 0.1)
				(type default)
			)
			(layer "F.Fab")
		)
		(fp_line
			(start -0.12065 0.3048)
			(end -0.67945 0.3048)
			(stroke
				(width 0.1)
				(type default)
			)
			(layer "F.Fab")
		)
		(fp_line
			(start 0.120396 0.2794)
			(end -0.12065 0.2794)
			(stroke
				(width 0.1)
				(type default)
			)
			(layer "F.Fab")
		)
		(fp_line
			(start 0.120396 0.3048)
			(end 0.120396 0.2794)
			(stroke
				(width 0.1)
				(type default)
			)
			(layer "F.Fab")
		)
		(fp_line
			(start 0.12065 -0.3048)
			(end 0.67945 -0.3048)
			(stroke
				(width 0.1)
				(type default)
			)
			(layer "F.Fab")
		)
		(fp_line
			(start 0.12065 -0.2794)
			(end 0.12065 -0.3048)
			(stroke
				(width 0.1)
				(type default)
			)
			(layer "F.Fab")
		)
		(fp_line
			(start 0.67945 -0.3048)
			(end 0.67945 0.3048)
			(stroke
				(width 0.1)
				(type default)
			)
			(layer "F.Fab")
		)
		(fp_line
			(start 0.67945 0.3048)
			(end 0.120396 0.3048)
			(stroke
				(width 0.1)
				(type default)
			)
			(layer "F.Fab")
		)
		(pad "1" smd circle
			(at -0.40005 0)
			(size 0 0)
			(layers "F.Cu" "F.Mask" "F.Paste")
			(net "USB_HUB_2_PGANG")
		)
		(pad "2" smd circle
			(at 0.40005 0)
			(size 0 0)
			(layers "F.Cu" "F.Mask" "F.Paste")
			(net "GND")
		)
	)
	(footprint ""
		(layer "F.Cu")
		(at 352.301048 -247.715024 90)
		(property "Reference" "C405"
			(at 0 0 90)
			(layer "F.SilkS")
			(hide yes)
			(effects
				(font
					(size 1.27 1.27)
				)
			)
		)
		(property "Value" ""
			(at 0 0 90)
			(layer "F.Fab")
			(effects
				(font
					(size 1.27 1.27)
				)
			)
		)
		(duplicate_pad_numbers_are_jumpers no)
		(fp_line
			(start 0.7874 -0.4064)
			(end 0.7874 0.4064)
			(stroke
				(width 0.1524)
				(type default)
			)
			(layer "F.SilkS")
		)
		(fp_line
			(start -0.7874 -0.4064)
			(end 0.7874 -0.4064)
			(stroke
				(width 0.1524)
				(type default)
			)
			(layer "F.SilkS")
		)
		(fp_line
			(start 0.7874 0.4064)
			(end -0.7874 0.4064)
			(stroke
				(width 0.1524)
				(type default)
			)
			(layer "F.SilkS")
		)
		(fp_line
			(start -0.7874 0.4064)
			(end -0.7874 -0.4064)
			(stroke
				(width 0.1524)
				(type default)
			)
			(layer "F.SilkS")
		)
		(fp_line
			(start -0.12065 -0.305054)
			(end -0.12065 -0.2794)
			(stroke
				(width 0.1)
				(type default)
			)
			(layer "F.Fab")
		)
		(fp_line
			(start -0.67945 -0.305054)
			(end -0.12065 -0.305054)
			(stroke
				(width 0.1)
				(type default)
			)
			(layer "F.Fab")
		)
		(fp_line
			(start 0.67945 -0.3048)
			(end 0.67945 0.3048)
			(stroke
				(width 0.1)
				(type default)
			)
			(layer "F.Fab")
		)
		(fp_line
			(start 0.12065 -0.3048)
			(end 0.67945 -0.3048)
			(stroke
				(width 0.1)
				(type default)
			)
			(layer "F.Fab")
		)
		(fp_line
			(start 0.12065 -0.2794)
			(end 0.12065 -0.3048)
			(stroke
				(width 0.1)
				(type default)
			)
			(layer "F.Fab")
		)
		(fp_line
			(start -0.12065 -0.2794)
			(end 0.12065 -0.2794)
			(stroke
				(width 0.1)
				(type default)
			)
			(layer "F.Fab")
		)
		(fp_line
			(start 0.120396 0.2794)
			(end -0.12065 0.2794)
			(stroke
				(width 0.1)
				(type default)
			)
			(layer "F.Fab")
		)
		(fp_line
			(start -0.12065 0.2794)
			(end -0.12065 0.3048)
			(stroke
				(width 0.1)
				(type default)
			)
			(layer "F.Fab")
		)
		(fp_line
			(start 0.67945 0.3048)
			(end 0.120396 0.3048)
			(stroke
				(width 0.1)
				(type default)
			)
			(layer "F.Fab")
		)
		(fp_line
			(start 0.120396 0.3048)
			(end 0.120396 0.2794)
			(stroke
				(width 0.1)
				(type default)
			)
			(layer "F.Fab")
		)
		(fp_line
			(start -0.12065 0.3048)
			(end -0.67945 0.3048)
			(stroke
				(width 0.1)
				(type default)
			)
			(layer "F.Fab")
		)
		(fp_line
			(start -0.67945 0.3048)
			(end -0.67945 -0.305054)
			(stroke
				(width 0.1)
				(type default)
			)
			(layer "F.Fab")
		)
		(pad "1" smd circle
			(at -0.40005 0 90)
			(size 0 0)
			(layers "F.Cu" "F.Mask" "F.Paste")
			(net "PVCCD_HV_CPU0")
		)
		(pad "2" smd circle
			(at 0.40005 0 90)
			(size 0 0)
			(layers "F.Cu" "F.Mask" "F.Paste")
			(net "GND")
		)
	)
	(footprint ""
		(layer "F.Cu")
		(at 32.191452 -165.761162)
		(property "Reference" "PC386"
			(at 0 0 0)
			(layer "F.SilkS")
			(hide yes)
			(effects
				(font
					(size 1.27 1.27)
				)
			)
		)
		(property "Value" ""
			(at 0 0 0)
			(layer "F.Fab")
			(effects
				(font
					(size 1.27 1.27)
				)
			)
		)
		(duplicate_pad_numbers_are_jumpers no)
		(fp_line
			(start -0.7874 -0.4064)
			(end 0.7874 -0.4064)
			(stroke
				(width 0.1524)
				(type default)
			)
			(layer "F.SilkS")
		)
		(fp_line
			(start -0.7874 0.4064)
			(end -0.7874 -0.4064)
			(stroke
				(width 0.1524)
				(type default)
			)
			(layer "F.SilkS")
		)
		(fp_line
			(start 0.7874 -0.4064)
			(end 0.7874 0.4064)
			(stroke
				(width 0.1524)
				(type default)
			)
			(layer "F.SilkS")
		)
		(fp_line
			(start 0.7874 0.4064)
			(end -0.7874 0.4064)
			(stroke
				(width 0.1524)
				(type default)
			)
			(layer "F.SilkS")
		)
		(fp_line
			(start -0.67945 -0.305054)
			(end -0.12065 -0.305054)
			(stroke
				(width 0.1)
				(type default)
			)
			(layer "F.Fab")
		)
		(fp_line
			(start -0.67945 0.3048)
			(end -0.67945 -0.305054)
			(stroke
				(width 0.1)
				(type default)
			)
			(layer "F.Fab")
		)
		(fp_line
			(start -0.12065 -0.305054)
			(end -0.12065 -0.2794)
			(stroke
				(width 0.1)
				(type default)
			)
			(layer "F.Fab")
		)
		(fp_line
			(start -0.12065 -0.2794)
			(end 0.12065 -0.2794)
			(stroke
				(width 0.1)
				(type default)
			)
			(layer "F.Fab")
		)
		(fp_line
			(start -0.12065 0.2794)
			(end -0.12065 0.3048)
			(stroke
				(width 0.1)
				(type default)
			)
			(layer "F.Fab")
		)
		(fp_line
			(start -0.12065 0.3048)
			(end -0.67945 0.3048)
			(stroke
				(width 0.1)
				(type default)
			)
			(layer "F.Fab")
		)
		(fp_line
			(start 0.120396 0.2794)
			(end -0.12065 0.2794)
			(stroke
				(width 0.1)
				(type default)
			)
			(layer "F.Fab")
		)
		(fp_line
			(start 0.120396 0.3048)
			(end 0.120396 0.2794)
			(stroke
				(width 0.1)
				(type default)
			)
			(layer "F.Fab")
		)
		(fp_line
			(start 0.12065 -0.3048)
			(end 0.67945 -0.3048)
			(stroke
				(width 0.1)
				(type default)
			)
			(layer "F.Fab")
		)
		(fp_line
			(start 0.12065 -0.2794)
			(end 0.12065 -0.3048)
			(stroke
				(width 0.1)
				(type default)
			)
			(layer "F.Fab")
		)
		(fp_line
			(start 0.67945 -0.3048)
			(end 0.67945 0.3048)
			(stroke
				(width 0.1)
				(type default)
			)
			(layer "F.Fab")
		)
		(fp_line
			(start 0.67945 0.3048)
			(end 0.120396 0.3048)
			(stroke
				(width 0.1)
				(type default)
			)
			(layer "F.Fab")
		)
		(pad "1" smd circle
			(at -0.40005 0)
			(size 0 0)
			(layers "F.Cu" "F.Mask" "F.Paste")
			(net "PVCCD_HV_CPU1_ISENSE_P")
		)
		(pad "2" smd circle
			(at 0.40005 0)
			(size 0 0)
			(layers "F.Cu" "F.Mask" "F.Paste")
			(net "GND")
		)
	)
	(footprint ""
		(layer "F.Cu")
		(at 370.232686 -357.11638 90)
		(property "Reference" "PR1310"
			(at 0 0 90)
			(layer "F.SilkS")
			(hide yes)
			(effects
				(font
					(size 1.27 1.27)
				)
			)
		)
		(property "Value" ""
			(at 0 0 90)
			(layer "F.Fab")
			(effects
				(font
					(size 1.27 1.27)
				)
			)
		)
		(duplicate_pad_numbers_are_jumpers no)
		(fp_line
			(start 0.7874 -0.4064)
			(end 0.7874 0.4064)
			(stroke
				(width 0.1524)
				(type default)
			)
			(layer "F.SilkS")
		)
		(fp_line
			(start -0.7874 -0.4064)
			(end 0.7874 -0.4064)
			(stroke
				(width 0.1524)
				(type default)
			)
			(layer "F.SilkS")
		)
		(fp_line
			(start 0.7874 0.4064)
			(end -0.7874 0.4064)
			(stroke
				(width 0.1524)
				(type default)
			)
			(layer "F.SilkS")
		)
		(fp_line
			(start -0.7874 0.4064)
			(end -0.7874 -0.4064)
			(stroke
				(width 0.1524)
				(type default)
			)
			(layer "F.SilkS")
		)
		(fp_line
			(start -0.12065 -0.305054)
			(end -0.12065 -0.2794)
			(stroke
				(width 0.1)
				(type default)
			)
			(layer "F.Fab")
		)
		(fp_line
			(start -0.67945 -0.305054)
			(end -0.12065 -0.305054)
			(stroke
				(width 0.1)
				(type default)
			)
			(layer "F.Fab")
		)
		(fp_line
			(start 0.67945 -0.3048)
			(end 0.67945 0.3048)
			(stroke
				(width 0.1)
				(type default)
			)
			(layer "F.Fab")
		)
		(fp_line
			(start 0.12065 -0.3048)
			(end 0.67945 -0.3048)
			(stroke
				(width 0.1)
				(type default)
			)
			(layer "F.Fab")
		)
		(fp_line
			(start 0.12065 -0.2794)
			(end 0.12065 -0.3048)
			(stroke
				(width 0.1)
				(type default)
			)
			(layer "F.Fab")
		)
		(fp_line
			(start -0.12065 -0.2794)
			(end 0.12065 -0.2794)
			(stroke
				(width 0.1)
				(type default)
			)
			(layer "F.Fab")
		)
		(fp_line
			(start 0.120396 0.2794)
			(end -0.12065 0.2794)
			(stroke
				(width 0.1)
				(type default)
			)
			(layer "F.Fab")
		)
		(fp_line
			(start -0.12065 0.2794)
			(end -0.12065 0.3048)
			(stroke
				(width 0.1)
				(type default)
			)
			(layer "F.Fab")
		)
		(fp_line
			(start 0.67945 0.3048)
			(end 0.120396 0.3048)
			(stroke
				(width 0.1)
				(type default)
			)
			(layer "F.Fab")
		)
		(fp_line
			(start 0.120396 0.3048)
			(end 0.120396 0.2794)
			(stroke
				(width 0.1)
				(type default)
			)
			(layer "F.Fab")
		)
		(fp_line
			(start -0.12065 0.3048)
			(end -0.67945 0.3048)
			(stroke
				(width 0.1)
				(type default)
			)
			(layer "F.Fab")
		)
		(fp_line
			(start -0.67945 0.3048)
			(end -0.67945 -0.305054)
			(stroke
				(width 0.1)
				(type default)
			)
			(layer "F.Fab")
		)
		(pad "1" smd circle
			(at -0.40005 0 90)
			(size 0 0)
			(layers "F.Cu" "F.Mask" "F.Paste")
			(net "PVPP_HBM_CPU0_FB")
		)
		(pad "2" smd circle
			(at 0.40005 0 90)
			(size 0 0)
			(layers "F.Cu" "F.Mask" "F.Paste")
			(net "SH_PVPP_HBM_CPU0_N")
		)
	)
	(footprint ""
		(layer "F.Cu")
		(at 22.100032 -176.329086)
		(property "Reference" "PR51"
			(at 0 0 0)
			(layer "F.SilkS")
			(hide yes)
			(effects
				(font
					(size 1.27 1.27)
				)
			)
		)
		(property "Value" ""
			(at 0 0 0)
			(layer "F.Fab")
			(effects
				(font
					(size 1.27 1.27)
				)
			)
		)
		(duplicate_pad_numbers_are_jumpers no)
		(fp_line
			(start -0.7874 -0.4064)
			(end 0.7874 -0.4064)
			(stroke
				(width 0.1524)
				(type default)
			)
			(layer "F.SilkS")
		)
		(fp_line
			(start -0.7874 0.4064)
			(end -0.7874 -0.4064)
			(stroke
				(width 0.1524)
				(type default)
			)
			(layer "F.SilkS")
		)
		(fp_line
			(start 0.7874 -0.4064)
			(end 0.7874 0.4064)
			(stroke
				(width 0.1524)
				(type default)
			)
			(layer "F.SilkS")
		)
		(fp_line
			(start 0.7874 0.4064)
			(end -0.7874 0.4064)
			(stroke
				(width 0.1524)
				(type default)
			)
			(layer "F.SilkS")
		)
		(fp_line
			(start -0.67945 -0.305054)
			(end -0.12065 -0.305054)
			(stroke
				(width 0.1)
				(type default)
			)
			(layer "F.Fab")
		)
		(fp_line
			(start -0.67945 0.3048)
			(end -0.67945 -0.305054)
			(stroke
				(width 0.1)
				(type default)
			)
			(layer "F.Fab")
		)
		(fp_line
			(start -0.12065 -0.305054)
			(end -0.12065 -0.2794)
			(stroke
				(width 0.1)
				(type default)
			)
			(layer "F.Fab")
		)
		(fp_line
			(start -0.12065 -0.2794)
			(end 0.12065 -0.2794)
			(stroke
				(width 0.1)
				(type default)
			)
			(layer "F.Fab")
		)
		(fp_line
			(start -0.12065 0.2794)
			(end -0.12065 0.3048)
			(stroke
				(width 0.1)
				(type default)
			)
			(layer "F.Fab")
		)
		(fp_line
			(start -0.12065 0.3048)
			(end -0.67945 0.3048)
			(stroke
				(width 0.1)
				(type default)
			)
			(layer "F.Fab")
		)
		(fp_line
			(start 0.120396 0.2794)
			(end -0.12065 0.2794)
			(stroke
				(width 0.1)
				(type default)
			)
			(layer "F.Fab")
		)
		(fp_line
			(start 0.120396 0.3048)
			(end 0.120396 0.2794)
			(stroke
				(width 0.1)
				(type default)
			)
			(layer "F.Fab")
		)
		(fp_line
			(start 0.12065 -0.3048)
			(end 0.67945 -0.3048)
			(stroke
				(width 0.1)
				(type default)
			)
			(layer "F.Fab")
		)
		(fp_line
			(start 0.12065 -0.2794)
			(end 0.12065 -0.3048)
			(stroke
				(width 0.1)
				(type default)
			)
			(layer "F.Fab")
		)
		(fp_line
			(start 0.67945 -0.3048)
			(end 0.67945 0.3048)
			(stroke
				(width 0.1)
				(type default)
			)
			(layer "F.Fab")
		)
		(fp_line
			(start 0.67945 0.3048)
			(end 0.120396 0.3048)
			(stroke
				(width 0.1)
				(type default)
			)
			(layer "F.Fab")
		)
		(pad "1" smd circle
			(at -0.40005 0)
			(size 0 0)
			(layers "F.Cu" "F.Mask" "F.Paste")
			(net "PVNN_MAIN_CPU1_FB")
		)
		(pad "2" smd circle
			(at 0.40005 0)
			(size 0 0)
			(layers "F.Cu" "F.Mask" "F.Paste")
			(net "GND")
		)
	)
	(footprint ""
		(layer "F.Cu")
		(at 157.351984 -81.90738 90)
		(property "Reference" "R3126"
			(at 0 0 90)
			(layer "F.SilkS")
			(hide yes)
			(effects
				(font
					(size 1.27 1.27)
				)
			)
		)
		(property "Value" ""
			(at 0 0 90)
			(layer "F.Fab")
			(effects
				(font
					(size 1.27 1.27)
				)
			)
		)
		(duplicate_pad_numbers_are_jumpers no)
		(fp_line
			(start 0.7874 -0.4064)
			(end 0.7874 0.4064)
			(stroke
				(width 0.1524)
				(type default)
			)
			(layer "F.SilkS")
		)
		(fp_line
			(start -0.7874 -0.4064)
			(end 0.7874 -0.4064)
			(stroke
				(width 0.1524)
				(type default)
			)
			(layer "F.SilkS")
		)
		(fp_line
			(start 0.7874 0.4064)
			(end -0.7874 0.4064)
			(stroke
				(width 0.1524)
				(type default)
			)
			(layer "F.SilkS")
		)
		(fp_line
			(start -0.7874 0.4064)
			(end -0.7874 -0.4064)
			(stroke
				(width 0.1524)
				(type default)
			)
			(layer "F.SilkS")
		)
		(fp_line
			(start -0.12065 -0.305054)
			(end -0.12065 -0.2794)
			(stroke
				(width 0.1)
				(type default)
			)
			(layer "F.Fab")
		)
		(fp_line
			(start -0.67945 -0.305054)
			(end -0.12065 -0.305054)
			(stroke
				(width 0.1)
				(type default)
			)
			(layer "F.Fab")
		)
		(fp_line
			(start 0.67945 -0.3048)
			(end 0.67945 0.3048)
			(stroke
				(width 0.1)
				(type default)
			)
			(layer "F.Fab")
		)
		(fp_line
			(start 0.12065 -0.3048)
			(end 0.67945 -0.3048)
			(stroke
				(width 0.1)
				(type default)
			)
			(layer "F.Fab")
		)
		(fp_line
			(start 0.12065 -0.2794)
			(end 0.12065 -0.3048)
			(stroke
				(width 0.1)
				(type default)
			)
			(layer "F.Fab")
		)
		(fp_line
			(start -0.12065 -0.2794)
			(end 0.12065 -0.2794)
			(stroke
				(width 0.1)
				(type default)
			)
			(layer "F.Fab")
		)
		(fp_line
			(start 0.120396 0.2794)
			(end -0.12065 0.2794)
			(stroke
				(width 0.1)
				(type default)
			)
			(layer "F.Fab")
		)
		(fp_line
			(start -0.12065 0.2794)
			(end -0.12065 0.3048)
			(stroke
				(width 0.1)
				(type default)
			)
			(layer "F.Fab")
		)
		(fp_line
			(start 0.67945 0.3048)
			(end 0.120396 0.3048)
			(stroke
				(width 0.1)
				(type default)
			)
			(layer "F.Fab")
		)
		(fp_line
			(start 0.120396 0.3048)
			(end 0.120396 0.2794)
			(stroke
				(width 0.1)
				(type default)
			)
			(layer "F.Fab")
		)
		(fp_line
			(start -0.12065 0.3048)
			(end -0.67945 0.3048)
			(stroke
				(width 0.1)
				(type default)
			)
			(layer "F.Fab")
		)
		(fp_line
			(start -0.67945 0.3048)
			(end -0.67945 -0.305054)
			(stroke
				(width 0.1)
				(type default)
			)
			(layer "F.Fab")
		)
		(pad "1" smd circle
			(at -0.40005 0 90)
			(size 0 0)
			(layers "F.Cu" "F.Mask" "F.Paste")
			(net "SMB_S3M_CPU1_PIROM_3V3AUX_SDA_R")
		)
		(pad "2" smd circle
			(at 0.40005 0 90)
			(size 0 0)
			(layers "F.Cu" "F.Mask" "F.Paste")
			(net "SMB_S3M_CPU1_PIROM_3V3AUX_SDA")
		)
	)
	(footprint ""
		(layer "F.Cu")
		(at 404.29053 -408.517344 -90)
		(property "Reference" "C891"
			(at 0 0 270)
			(layer "F.SilkS")
			(hide yes)
			(effects
				(font
					(size 1.27 1.27)
				)
			)
		)
		(property "Value" ""
			(at 0 0 270)
			(layer "F.Fab")
			(effects
				(font
					(size 1.27 1.27)
				)
			)
		)
		(duplicate_pad_numbers_are_jumpers no)
		(fp_line
			(start -0.299974 0.150114)
			(end -0.299974 -0.150114)
			(stroke
				(width 0.1)
				(type default)
			)
			(layer "F.Fab")
		)
		(fp_line
			(start 0.299974 0.150114)
			(end -0.299974 0.150114)
			(stroke
				(width 0.1)
				(type default)
			)
			(layer "F.Fab")
		)
		(fp_line
			(start -0.299974 -0.150114)
			(end 0.299974 -0.150114)
			(stroke
				(width 0.1)
				(type default)
			)
			(layer "F.Fab")
		)
		(fp_line
			(start 0.299974 -0.150114)
			(end 0.299974 0.150114)
			(stroke
				(width 0.1)
				(type default)
			)
			(layer "F.Fab")
		)
		(pad "1" smd rect
			(at -0.2667 0 270)
			(size 0.3048 0.381)
			(layers "F.Cu" "F.Mask" "F.Paste")
			(net "P5E_CPU0_PE3_TX_C_DP<5>")
		)
		(pad "2" smd rect
			(at 0.2667 0 270)
			(size 0.3048 0.381)
			(layers "F.Cu" "F.Mask" "F.Paste")
			(net "P5E_CPU0_PE3_TX_DP<5>")
		)
	)
)
